# TIMECARD (Time Appliance Project (Time Card)) — schematic netlist excerpt (pin names and nets, part order shuffled) for the footprints in the layout excerpt that follows; sources: Cadence DE-HDL packaged netlist, KiCad conversion of R4006-B0001-02_R01.brd

R232  RESISTOR  2.1KOHM 1%  pkg SMC_0402R  page 31 : \1\ = SG ; \2\ = UNNAMED_515_ISL80101IRAJZDFN10_
C120  CAPACITOR  4.7UF 6.3V 20%  pkg SMC_0402R_H026  page 14 : \1\ = XP1R8V_FPGA_VCCAUX ; \2\ = SG

(kicad_pcb
	(version 20260206)
	(generator "pcbnew")
	(generator_version "10.0")
	(general
		(thickness 1.6)
		(legacy_teardrops no)
	)
	(paper "A4")
	(title_block
		(title "timecard-production-celestica-r4006 — R4006-B0001-02_R01.brd")
		(comment 1 "Time Appliance Project (Time Card) / footprints 903-904 of 1113")
	)
	(layers
		(0 "F.Cu" signal "TOP")
		(4 "In1.Cu" signal "L02_GND1")
		(6 "In2.Cu" signal "L03_SIG1")
		(8 "In3.Cu" signal "L04_GND2")
		(10 "In4.Cu" signal "L05_VCC1")
		(12 "In5.Cu" signal "L06_VCC2")
		(14 "In6.Cu" signal "L07_GND3")
		(16 "In7.Cu" signal "L08_SIG2")
		(18 "In8.Cu" signal "L09_GND4")
		(2 "B.Cu" signal "BOTTOM")
		(9 "F.Adhes" user "F.Adhesive")
		(11 "B.Adhes" user "B.Adhesive")
		(13 "F.Paste" user "Package Geometry/Pastemask Top")
		(15 "B.Paste" user "Package Geometry/Pastemask Bottom")
		(5 "F.SilkS" user "Ref Des/Silkscreen Top")
		(7 "B.SilkS" user "Ref Des/Silkscreen Bottom")
		(1 "F.Mask" user "Board Geometry/Soldermask Top")
		(3 "B.Mask" user "Board Geometry/Soldermask Bottom")
		(17 "Dwgs.User" user "User.Drawings")
		(19 "Cmts.User" user "User.Comments")
		(21 "Eco1.User" user "User.Eco1")
		(23 "Eco2.User" user "User.Eco2")
		(25 "Edge.Cuts" user "Board Geometry/Outline")
		(27 "Margin" user)
		(31 "F.CrtYd" user "Package Geometry/Place Bound Top")
		(29 "B.CrtYd" user "Package Geometry/Place Bound Bottom")
		(35 "F.Fab" user "Ref Des/Assembly Top")
		(33 "B.Fab" user "Ref Des/Assembly Bottom")
	)
	(footprint ""
		(layer "B.Cu")
		(at 141.1478 -18.4404 90)
		(property "Reference" "R232"
			(at 6.4516 -0.21717 270)
			(unlocked yes)
			(layer "B.SilkS")
			(effects
				(font
					(size 0.7874 0.5842)
					(thickness 0.1524)
				)
				(justify mirror)
			)
		)
		(property "Value" "VAL*"
			(at -0.0508 2.245106 90)
			(unlocked yes)
			(layer "B.Fab")
			(hide yes)
			(effects
				(font
					(size 0.7874 0.5842)
					(thickness 0.1524)
				)
				(justify mirror)
			)
		)
		(property "Tolerance" "TOL*"
			(at -0.0508 3.261106 90)
			(unlocked yes)
			(layer "Cmts.User")
			(hide yes)
			(effects
				(font
					(size 0.7874 0.5842)
					(thickness 0.1524)
				)
				(justify mirror)
			)
		)
		(property "Device Type" "RESISTOR-G155-02101-01,2.1KOHMA"
			(at -0.0762 1.254506 90)
			(unlocked yes)
			(layer "B.Fab")
			(hide yes)
			(effects
				(font
					(size 0.7874 0.5842)
					(thickness 0.1524)
				)
				(justify mirror)
			)
		)
		(property "User Part Number" "PARTNUM*"
			(at -0.0762 4.302506 90)
			(unlocked yes)
			(layer "Cmts.User")
			(hide yes)
			(effects
				(font
					(size 0.7874 0.5842)
					(thickness 0.1524)
				)
				(justify mirror)
			)
		)
		(duplicate_pad_numbers_are_jumpers no)
		(fp_line
			(start 1.143 -0.5588)
			(end 1.143 0.5588)
			(stroke
				(width 0.1)
				(type default)
			)
			(layer "B.SilkS")
		)
		(fp_line
			(start -1.143 -0.5588)
			(end 1.143 -0.5588)
			(stroke
				(width 0.1)
				(type default)
			)
			(layer "B.SilkS")
		)
		(fp_line
			(start 1.143 0.5588)
			(end -1.143 0.5588)
			(stroke
				(width 0.1)
				(type default)
			)
			(layer "B.SilkS")
		)
		(fp_line
			(start -1.143 0.5588)
			(end -1.143 -0.5588)
			(stroke
				(width 0.1)
				(type default)
			)
			(layer "B.SilkS")
		)
		(fp_rect
			(start 1.143 0.5588)
			(end -1.143 -0.5588)
			(stroke
				(width 0)
				(type default)
			)
			(fill no)
			(layer "B.CrtYd")
		)
		(fp_line
			(start 0.508 -0.3048)
			(end 0.508 0.3048)
			(stroke
				(width 0.1)
				(type default)
			)
			(layer "B.Fab")
		)
		(fp_line
			(start -0.508 -0.3048)
			(end 0.508 -0.3048)
			(stroke
				(width 0.1)
				(type default)
			)
			(layer "B.Fab")
		)
		(fp_line
			(start 0.508 0.3048)
			(end -0.508 0.3048)
			(stroke
				(width 0.1)
				(type default)
			)
			(layer "B.Fab")
		)
		(fp_line
			(start -0.508 0.3048)
			(end -0.508 -0.3048)
			(stroke
				(width 0.1)
				(type default)
			)
			(layer "B.Fab")
		)
		(pad "1" smd rect
			(at 0.5334 0 270)
			(size 0.7112 0.6096)
			(layers "B.Cu" "B.Mask" "B.Paste")
			(net "SG")
		)
		(pad "2" smd rect
			(at -0.5334 0 270)
			(size 0.7112 0.6096)
			(layers "B.Cu" "B.Mask" "B.Paste")
			(net "UNNAMED_515_ISL80101IRAJZDFN10_")
		)
		(zone
			(layer "B.Cu")
			(hatch none 0.5)
			(connect_pads
				(clearance 0)
			)
			(min_thickness 0.25)
			(keepout
				(tracks allowed)
				(vias not_allowed)
				(pads allowed)
				(copperpour not_allowed)
				(footprints allowed)
			)
			(placement
				(enabled no)
				(sheetname "")
			)
			(fill
				(thermal_gap 0.5)
				(thermal_bridge_width 0.5)
				(island_removal_mode 0)
			)
			(polygon
				(pts
					(xy 141.4526 -18.5166) (xy 140.843 -18.5166) (xy 140.843 -18.3642) (xy 141.4526 -18.3642)
				)
			)
		)
	)
	(footprint ""
		(layer "B.Cu")
		(at 106.847132 -41.323006 90)
		(property "Reference" "C120"
			(at -1.015746 -41.382442 270)
			(unlocked yes)
			(layer "B.SilkS")
			(effects
				(font
					(size 0.635 0.4064)
					(thickness 0.1524)
				)
				(justify mirror)
			)
		)
		(property "Value" "VAL*"
			(at 0 3.718306 90)
			(unlocked yes)
			(layer "B.Fab")
			(hide yes)
			(effects
				(font
					(size 0.7874 0.5842)
					(thickness 0.127)
				)
				(justify mirror)
			)
		)
		(property "Device Type" "CAPACITOR-G105-0F475-BM,4.7UF,A"
			(at 0 1.432306 90)
			(unlocked yes)
			(layer "B.Fab")
			(hide yes)
			(effects
				(font
					(size 0.7874 0.5842)
					(thickness 0.127)
				)
				(justify mirror)
			)
		)
		(property "User Part Number" "PARTNUM*"
			(at 0 2.575306 90)
			(unlocked yes)
			(layer "Cmts.User")
			(hide yes)
			(effects
				(font
					(size 0.7874 0.5842)
					(thickness 0.127)
				)
				(justify mirror)
			)
		)
		(property "Tolerance" "TOL*"
			(at 0 4.861306 90)
			(unlocked yes)
			(layer "Cmts.User")
			(hide yes)
			(effects
				(font
					(size 0.7874 0.5842)
					(thickness 0.127)
				)
				(justify mirror)
			)
		)
		(duplicate_pad_numbers_are_jumpers no)
		(fp_line
			(start 0.970026 -0.4699)
			(end -0.970026 -0.4699)
			(stroke
				(width 0.1)
				(type default)
			)
			(layer "B.SilkS")
		)
		(fp_line
			(start -0.970026 -0.4699)
			(end -0.970026 0.4699)
			(stroke
				(width 0.1)
				(type default)
			)
			(layer "B.SilkS")
		)
		(fp_line
			(start 0.970026 0.4699)
			(end 0.970026 -0.4699)
			(stroke
				(width 0.1)
				(type default)
			)
			(layer "B.SilkS")
		)
		(fp_line
			(start -0.970026 0.4699)
			(end 0.970026 0.4699)
			(stroke
				(width 0.1)
				(type default)
			)
			(layer "B.SilkS")
		)
		(fp_poly
			(pts
				(xy 0.970026 0.4699) (xy -0.970026 0.4699) (xy -0.970026 -0.4699) (xy 0.970026 -0.4699)
			)
			(stroke
				(width 0)
				(type default)
			)
			(fill no)
			(layer "B.CrtYd")
		)
		(fp_line
			(start 0.508 -0.3048)
			(end -0.508 -0.3048)
			(stroke
				(width 0.1)
				(type default)
			)
			(layer "B.Fab")
		)
		(fp_line
			(start -0.508 -0.3048)
			(end -0.508 0.3048)
			(stroke
				(width 0.1)
				(type default)
			)
			(layer "B.Fab")
		)
		(fp_line
			(start 0.508 0.3048)
			(end 0.508 -0.3048)
			(stroke
				(width 0.1)
				(type default)
			)
			(layer "B.Fab")
		)
		(fp_line
			(start -0.508 0.3048)
			(end 0.508 0.3048)
			(stroke
				(width 0.1)
				(type default)
			)
			(layer "B.Fab")
		)
		(pad "1" smd circle
			(at 0.500126 0 270)
			(size 0.635 0.635)
			(layers "B.Cu" "B.Mask" "B.Paste")
			(net "XP1R8V_FPGA_VCCAUX")
		)
		(pad "2" smd circle
			(at -0.500126 0 270)
			(size 0.635 0.635)
			(layers "B.Cu" "B.Mask" "B.Paste")
			(net "SG")
		)
	)
)
